(kicad_pcb
	(version 20260206)
	(generator "pcbnew")
	(generator_version "10.0")
	(general
		(thickness 1.6)
		(legacy_teardrops no)
	)
	(paper "A4")
	(title_block
		(title "v1-chassis-manager — T6M_CM_d_v01_1031_1645.brd")
		(comment 1 "Open CloudServer (Microsoft) / footprints 254-262 of 2512")
	)
	(layers
		(0 "F.Cu" signal "TOP")
		(4 "In1.Cu" signal "GND1")
		(6 "In2.Cu" signal "IN1")
		(8 "In3.Cu" signal "VCC1")
		(10 "In4.Cu" signal "VCC2")
		(12 "In5.Cu" signal "GND2")
		(14 "In6.Cu" signal "IN2")
		(16 "In7.Cu" signal "IN3")
		(18 "In8.Cu" signal "GND3")
		(2 "B.Cu" signal "BOTTOM")
		(9 "F.Adhes" user "F.Adhesive")
		(11 "B.Adhes" user "B.Adhesive")
		(13 "F.Paste" user "Package Geometry/Pastemask Top")
		(15 "B.Paste" user "Package Geometry/Pastemask Bottom")
		(5 "F.SilkS" user "Ref Des/Silkscreen Top")
		(7 "B.SilkS" user "Ref Des/Silkscreen Bottom")
		(1 "F.Mask" user "Board Geometry/Soldermask Top")
		(3 "B.Mask" user "Board Geometry/Soldermask Bottom")
		(17 "Dwgs.User" user "User.Drawings")
		(19 "Cmts.User" user "User.Comments")
		(21 "Eco1.User" user "User.Eco1")
		(23 "Eco2.User" user "User.Eco2")
		(25 "Edge.Cuts" user "Board Geometry/Outline")
		(27 "Margin" user)
		(31 "F.CrtYd" user "Package Geometry/Place Bound Top")
		(29 "B.CrtYd" user "Package Geometry/Place Bound Bottom")
		(35 "F.Fab" user "Ref Des/Assembly Top")
		(33 "B.Fab" user "Ref Des/Assembly Bottom")
	)
	(footprint ""
		(layer "F.Cu")
		(at 94.211394 -186.806586)
		(property "Reference" "R905"
			(at -1.182878 -7.236714 0)
			(unlocked yes)
			(layer "F.SilkS")
			(effects
				(font
					(size 0.7874 0.5842)
					(thickness 0.1524)
				)
				(justify left)
			)
		)
		(property "Value" ""
			(at 0 0 0)
			(layer "F.Fab")
			(effects
				(font
					(size 1.27 1.27)
				)
			)
		)
		(duplicate_pad_numbers_are_jumpers no)
		(fp_line
			(start -0.7874 -0.4064)
			(end 0.7874 -0.4064)
			(stroke
				(width 0.1524)
				(type default)
			)
			(layer "F.SilkS")
		)
		(fp_line
			(start -0.7874 0.4064)
			(end -0.7874 -0.4064)
			(stroke
				(width 0.1524)
				(type default)
			)
			(layer "F.SilkS")
		)
		(fp_line
			(start 0.7874 -0.4064)
			(end 0.7874 0.4064)
			(stroke
				(width 0.1524)
				(type default)
			)
			(layer "F.SilkS")
		)
		(fp_line
			(start 0.7874 0.4064)
			(end -0.7874 0.4064)
			(stroke
				(width 0.1524)
				(type default)
			)
			(layer "F.SilkS")
		)
		(fp_poly
			(pts
				(xy -0.508 0.2794) (xy -0.508 0.2286) (xy -0.635 0.2286) (xy -0.635 -0.254) (xy -0.5334 -0.254)
				(xy -0.5334 -0.2794) (xy 0.5334 -0.2794) (xy 0.5334 -0.254) (xy 0.635 -0.254) (xy 0.635 0.254) (xy 0.5334 0.254)
				(xy 0.5334 0.2794)
			)
			(stroke
				(width 0)
				(type default)
			)
			(fill no)
			(layer "F.CrtYd")
		)
		(pad "1" smd rect
			(at 0.40005 0)
			(size 0.4572 0.508)
			(layers "F.Cu" "F.Mask" "F.Paste")
			(net "T5_NODE4_EN")
		)
		(pad "2" smd rect
			(at -0.40005 0)
			(size 0.4572 0.508)
			(layers "F.Cu" "F.Mask" "F.Paste")
			(net "T5_NODE4_EN_R")
		)
	)
	(footprint ""
		(layer "F.Cu")
		(at 84.458048 -128.998726 -90)
		(property "Reference" "R1253"
			(at 5.940044 4.586224 90)
			(unlocked yes)
			(layer "F.SilkS")
			(effects
				(font
					(size 0.7874 0.5842)
					(thickness 0.1524)
				)
				(justify left)
			)
		)
		(property "Value" ""
			(at 0 0 270)
			(layer "F.Fab")
			(effects
				(font
					(size 1.27 1.27)
				)
			)
		)
		(duplicate_pad_numbers_are_jumpers no)
		(fp_line
			(start -0.7874 0.4064)
			(end -0.7874 -0.4064)
			(stroke
				(width 0.1524)
				(type default)
			)
			(layer "F.SilkS")
		)
		(fp_line
			(start 0.7874 0.4064)
			(end -0.7874 0.4064)
			(stroke
				(width 0.1524)
				(type default)
			)
			(layer "F.SilkS")
		)
		(fp_line
			(start -0.7874 -0.4064)
			(end 0.7874 -0.4064)
			(stroke
				(width 0.1524)
				(type default)
			)
			(layer "F.SilkS")
		)
		(fp_line
			(start 0.7874 -0.4064)
			(end 0.7874 0.4064)
			(stroke
				(width 0.1524)
				(type default)
			)
			(layer "F.SilkS")
		)
		(fp_poly
			(pts
				(xy -0.508 0.2794) (xy -0.508 0.2286) (xy -0.635 0.2286) (xy -0.635 -0.254) (xy -0.5334 -0.254)
				(xy -0.5334 -0.2794) (xy 0.5334 -0.2794) (xy 0.5334 -0.254) (xy 0.635 -0.254) (xy 0.635 0.254) (xy 0.5334 0.254)
				(xy 0.5334 0.2794)
			)
			(stroke
				(width 0)
				(type default)
			)
			(fill no)
			(layer "F.CrtYd")
		)
		(pad "1" smd rect
			(at 0.40005 0 270)
			(size 0.4572 0.508)
			(layers "F.Cu" "F.Mask" "F.Paste")
			(net "PORT80_LOUT1")
		)
		(pad "2" smd rect
			(at -0.40005 0 270)
			(size 0.4572 0.508)
			(layers "F.Cu" "F.Mask" "F.Paste")
			(net "N53313464")
		)
	)
	(footprint ""
		(layer "F.Cu")
		(at 94.451932 -176.338992)
		(property "Reference" "R738"
			(at 86.67369 74.174096 0)
			(unlocked yes)
			(layer "F.SilkS")
			(effects
				(font
					(size 0.7874 0.5842)
					(thickness 0.1524)
				)
				(justify left)
			)
		)
		(property "Value" ""
			(at 0 0 0)
			(layer "F.Fab")
			(effects
				(font
					(size 1.27 1.27)
				)
			)
		)
		(duplicate_pad_numbers_are_jumpers no)
		(fp_line
			(start -0.7874 -0.4064)
			(end 0.7874 -0.4064)
			(stroke
				(width 0.1524)
				(type default)
			)
			(layer "F.SilkS")
		)
		(fp_line
			(start -0.7874 0.4064)
			(end -0.7874 -0.4064)
			(stroke
				(width 0.1524)
				(type default)
			)
			(layer "F.SilkS")
		)
		(fp_line
			(start 0.7874 -0.4064)
			(end 0.7874 0.4064)
			(stroke
				(width 0.1524)
				(type default)
			)
			(layer "F.SilkS")
		)
		(fp_line
			(start 0.7874 0.4064)
			(end -0.7874 0.4064)
			(stroke
				(width 0.1524)
				(type default)
			)
			(layer "F.SilkS")
		)
		(fp_poly
			(pts
				(xy -0.508 0.2794) (xy -0.508 0.2286) (xy -0.635 0.2286) (xy -0.635 -0.254) (xy -0.5334 -0.254)
				(xy -0.5334 -0.2794) (xy 0.5334 -0.2794) (xy 0.5334 -0.254) (xy 0.635 -0.254) (xy 0.635 0.254) (xy 0.5334 0.254)
				(xy 0.5334 0.2794)
			)
			(stroke
				(width 0)
				(type default)
			)
			(fill no)
			(layer "F.CrtYd")
		)
		(pad "1" smd rect
			(at 0.40005 0)
			(size 0.4572 0.508)
			(layers "F.Cu" "F.Mask" "F.Paste")
			(net "N21698939")
		)
		(pad "2" smd rect
			(at -0.40005 0)
			(size 0.4572 0.508)
			(layers "F.Cu" "F.Mask" "F.Paste")
			(net "P3V3_NODE1")
		)
	)
	(footprint ""
		(layer "F.Cu")
		(at 109.291374 -160.395158 90)
		(property "Reference" "U126"
			(at -69.92493 88.239346 0)
			(unlocked yes)
			(layer "F.SilkS")
			(effects
				(font
					(size 0.7874 0.5842)
					(thickness 0.1524)
				)
			)
		)
		(property "Value" ""
			(at 0 0 90)
			(layer "F.Fab")
			(effects
				(font
					(size 1.27 1.27)
				)
			)
		)
		(duplicate_pad_numbers_are_jumpers no)
		(fp_line
			(start 1.651 -1.905)
			(end 1.651 1.905)
			(stroke
				(width 0.1524)
				(type default)
			)
			(layer "F.SilkS")
		)
		(fp_line
			(start -1.651 -1.905)
			(end 1.651 -1.905)
			(stroke
				(width 0.1524)
				(type default)
			)
			(layer "F.SilkS")
		)
		(fp_line
			(start 1.651 1.905)
			(end -1.651 1.905)
			(stroke
				(width 0.1524)
				(type default)
			)
			(layer "F.SilkS")
		)
		(fp_line
			(start -1.651 1.905)
			(end -1.651 -1.905)
			(stroke
				(width 0.1524)
				(type default)
			)
			(layer "F.SilkS")
		)
		(fp_poly
			(pts
				(xy -1.524 0.7112) (xy -1.524 1.7526) (xy -0.508 1.7526) (xy -0.508 0.6985) (xy 0.508 0.6985) (xy 0.508 1.7526)
				(xy 1.524 1.7526) (xy 1.524 0.6985) (xy 1.524 -0.6985) (xy 0.508 -0.6985) (xy 0.508 -1.7526) (xy -0.508 -1.7526)
				(xy -0.508 -0.6985) (xy -1.524 -0.6985) (xy -1.524 0.6985)
			)
			(stroke
				(width 0)
				(type default)
			)
			(fill no)
			(layer "F.CrtYd")
		)
		(fp_text user "D"
			(at 1.691386 -2.260092 0)
			(unlocked yes)
			(layer "F.SilkS")
			(effects
				(font
					(size 0.635 0.4064)
					(thickness 0.1524)
				)
			)
		)
		(fp_text user "G"
			(at -1.093978 0.053086 0)
			(unlocked yes)
			(layer "F.SilkS")
			(effects
				(font
					(size 0.635 0.4064)
					(thickness 0.1524)
				)
			)
		)
		(fp_text user "S"
			(at 1.208532 2.574036 0)
			(unlocked yes)
			(layer "F.SilkS")
			(effects
				(font
					(size 0.635 0.4064)
					(thickness 0.1524)
				)
			)
		)
		(pad "D" smd rect
			(at 0 -1.1176 90)
			(size 1.016 1.27)
			(layers "F.Cu" "F.Mask" "F.Paste")
			(net "I2C_PSU2_SCL")
		)
		(pad "G" smd rect
			(at -1.016 1.1176 90)
			(size 1.016 1.27)
			(layers "F.Cu" "F.Mask" "F.Paste")
			(net "PMBUS2_EN")
		)
		(pad "S" smd rect
			(at 1.016 1.1176 90)
			(size 1.016 1.27)
			(layers "F.Cu" "F.Mask" "F.Paste")
			(net "I2C_PSU2_SCL_MOS")
		)
	)
	(footprint ""
		(layer "F.Cu")
		(at 93.854778 -117.955314 -90)
		(property "Reference" "TP173"
			(at 0 0 270)
			(layer "F.SilkS")
			(hide yes)
			(effects
				(font
					(size 1.27 1.27)
				)
			)
		)
		(property "Value" ""
			(at 0 0 270)
			(layer "F.Fab")
			(effects
				(font
					(size 1.27 1.27)
				)
			)
		)
		(duplicate_pad_numbers_are_jumpers no)
		(fp_poly
			(pts
				(arc
					(start 0 0.3302)
					(mid 0 -0.3302)
					(end 0 0.3302)
				)
			)
			(stroke
				(width 0)
				(type default)
			)
			(fill no)
			(layer "B.CrtYd")
		)
		(pad "1" thru_hole circle
			(at 0 0 270)
			(size 0.508 0.508)
			(drill 0.254)
			(layers "*.Cu" "*.Mask")
			(remove_unused_layers no)
			(net "N53313289")
			(clearance 0.127)
			(thermal_gap 0.127)
			(padstack
				(mode front_inner_back)
				(layer "Inner"
					(shape circle)
					(size 0.508 0.508)
					(clearance 0.127)
				)
				(layer "B.Cu"
					(shape circle)
					(size 0.6604 0.6604)
					(clearance 0.0508)
				)
			)
		)
	)
	(footprint ""
		(layer "F.Cu")
		(at 104.514142 -158.277052 90)
		(property "Reference" "PR13"
			(at -1.761998 2.672588 90)
			(unlocked yes)
			(layer "F.SilkS")
			(effects
				(font
					(size 0.635 0.4064)
					(thickness 0.1524)
				)
				(justify left)
			)
		)
		(property "Value" ""
			(at 0 0 90)
			(layer "F.Fab")
			(effects
				(font
					(size 1.27 1.27)
				)
			)
		)
		(duplicate_pad_numbers_are_jumpers no)
		(fp_line
			(start 0.7874 -0.4064)
			(end 0.7874 0.4064)
			(stroke
				(width 0.1524)
				(type default)
			)
			(layer "F.SilkS")
		)
		(fp_line
			(start -0.7874 -0.4064)
			(end 0.7874 -0.4064)
			(stroke
				(width 0.1524)
				(type default)
			)
			(layer "F.SilkS")
		)
		(fp_line
			(start 0.7874 0.4064)
			(end -0.7874 0.4064)
			(stroke
				(width 0.1524)
				(type default)
			)
			(layer "F.SilkS")
		)
		(fp_line
			(start -0.7874 0.4064)
			(end -0.7874 -0.4064)
			(stroke
				(width 0.1524)
				(type default)
			)
			(layer "F.SilkS")
		)
		(fp_poly
			(pts
				(xy -0.508 0.2794) (xy -0.508 0.2286) (xy -0.635 0.2286) (xy -0.635 -0.254) (xy -0.5334 -0.254)
				(xy -0.5334 -0.2794) (xy 0.5334 -0.2794) (xy 0.5334 -0.254) (xy 0.635 -0.254) (xy 0.635 0.254) (xy 0.5334 0.254)
				(xy 0.5334 0.2794)
			)
			(stroke
				(width 0)
				(type default)
			)
			(fill no)
			(layer "F.CrtYd")
		)
		(pad "1" smd rect
			(at 0.40005 0 90)
			(size 0.4572 0.508)
			(layers "F.Cu" "F.Mask" "F.Paste")
			(net "P1V8_STB_NODE1_VREG5")
		)
		(pad "2" smd rect
			(at -0.40005 0 90)
			(size 0.4572 0.508)
			(layers "F.Cu" "F.Mask" "F.Paste")
			(net "PWRGD_NODE1_P1V8_STB_PG")
		)
	)
	(footprint ""
		(layer "F.Cu")
		(at 29.050488 -130.589782 90)
		(property "Reference" "C834"
			(at -0.586486 -2.10439 90)
			(unlocked yes)
			(layer "F.SilkS")
			(effects
				(font
					(size 0.7874 0.5842)
					(thickness 0.1524)
				)
				(justify left)
			)
		)
		(property "Value" ""
			(at 0 0 90)
			(layer "F.Fab")
			(effects
				(font
					(size 1.27 1.27)
				)
			)
		)
		(duplicate_pad_numbers_are_jumpers no)
		(fp_line
			(start 0.7874 -0.4064)
			(end 0.7874 0.4064)
			(stroke
				(width 0.1524)
				(type default)
			)
			(layer "F.SilkS")
		)
		(fp_line
			(start -0.7874 -0.4064)
			(end 0.7874 -0.4064)
			(stroke
				(width 0.1524)
				(type default)
			)
			(layer "F.SilkS")
		)
		(fp_line
			(start 0 0.381)
			(end 0 -0.381)
			(stroke
				(width 0.1524)
				(type default)
			)
			(layer "F.SilkS")
		)
		(fp_line
			(start 0.7874 0.4064)
			(end -0.7874 0.4064)
			(stroke
				(width 0.1524)
				(type default)
			)
			(layer "F.SilkS")
		)
		(fp_line
			(start -0.7874 0.4064)
			(end -0.7874 -0.4064)
			(stroke
				(width 0.1524)
				(type default)
			)
			(layer "F.SilkS")
		)
		(fp_poly
			(pts
				(xy -0.5334 0.254) (xy -0.635 0.254) (xy -0.635 0.2286) (xy -0.635 -0.254) (xy -0.5334 -0.254) (xy -0.5334 -0.2794)
				(xy 0.5334 -0.2794) (xy 0.5334 -0.254) (xy 0.635 -0.254) (xy 0.635 0.254) (xy 0.5334 0.254) (xy 0.5334 0.2794)
				(xy -0.508 0.2794) (xy -0.5334 0.2794)
			)
			(stroke
				(width 0)
				(type default)
			)
			(fill no)
			(layer "F.CrtYd")
		)
		(pad "1" smd rect
			(at 0.40005 0 90)
			(size 0.4572 0.508)
			(layers "F.Cu" "F.Mask" "F.Paste")
			(net "GND")
		)
		(pad "2" smd rect
			(at -0.40005 0 90)
			(size 0.4572 0.508)
			(layers "F.Cu" "F.Mask" "F.Paste")
			(net "PWRGD_NODE1_P1V538_BMC_PG")
		)
	)
	(footprint ""
		(layer "F.Cu")
		(at 165.811454 -163.848288)
		(property "Reference" "R577"
			(at 1.22936 0.186182 0)
			(unlocked yes)
			(layer "F.SilkS")
			(effects
				(font
					(size 0.7874 0.5842)
					(thickness 0.1524)
				)
				(justify left)
			)
		)
		(property "Value" ""
			(at 0 0 0)
			(layer "F.Fab")
			(effects
				(font
					(size 1.27 1.27)
				)
			)
		)
		(duplicate_pad_numbers_are_jumpers no)
		(fp_line
			(start -0.7874 -0.4064)
			(end 0.7874 -0.4064)
			(stroke
				(width 0.1524)
				(type default)
			)
			(layer "F.SilkS")
		)
		(fp_line
			(start -0.7874 0.4064)
			(end -0.7874 -0.4064)
			(stroke
				(width 0.1524)
				(type default)
			)
			(layer "F.SilkS")
		)
		(fp_line
			(start 0.7874 -0.4064)
			(end 0.7874 0.4064)
			(stroke
				(width 0.1524)
				(type default)
			)
			(layer "F.SilkS")
		)
		(fp_line
			(start 0.7874 0.4064)
			(end -0.7874 0.4064)
			(stroke
				(width 0.1524)
				(type default)
			)
			(layer "F.SilkS")
		)
		(fp_poly
			(pts
				(xy -0.508 0.2794) (xy -0.508 0.2286) (xy -0.635 0.2286) (xy -0.635 -0.254) (xy -0.5334 -0.254)
				(xy -0.5334 -0.2794) (xy 0.5334 -0.2794) (xy 0.5334 -0.254) (xy 0.635 -0.254) (xy 0.635 0.254) (xy 0.5334 0.254)
				(xy 0.5334 0.2794)
			)
			(stroke
				(width 0)
				(type default)
			)
			(fill no)
			(layer "F.CrtYd")
		)
		(pad "1" smd rect
			(at 0.40005 0)
			(size 0.4572 0.508)
			(layers "F.Cu" "F.Mask" "F.Paste")
			(net "SPI_LAN2_NVM_SI")
		)
		(pad "2" smd rect
			(at -0.40005 0)
			(size 0.4572 0.508)
			(layers "F.Cu" "F.Mask" "F.Paste")
			(net "LAN2_NVM_SI_R")
		)
	)
	(footprint ""
		(layer "F.Cu")
		(at 67.67576 -188.126624 90)
		(property "Reference" "C637"
			(at 4.548886 -0.5842 90)
			(unlocked yes)
			(layer "F.SilkS")
			(effects
				(font
					(size 0.7874 0.5842)
					(thickness 0.1524)
				)
				(justify left)
			)
		)
		(property "Value" ""
			(at 0 0 90)
			(layer "F.Fab")
			(effects
				(font
					(size 1.27 1.27)
				)
			)
		)
		(duplicate_pad_numbers_are_jumpers no)
		(fp_line
			(start 0.7874 -0.4064)
			(end 0.7874 0.4064)
			(stroke
				(width 0.1524)
				(type default)
			)
			(layer "F.SilkS")
		)
		(fp_line
			(start -0.7874 -0.4064)
			(end 0.7874 -0.4064)
			(stroke
				(width 0.1524)
				(type default)
			)
			(layer "F.SilkS")
		)
		(fp_line
			(start 0 0.381)
			(end 0 -0.381)
			(stroke
				(width 0.1524)
				(type default)
			)
			(layer "F.SilkS")
		)
		(fp_line
			(start 0.7874 0.4064)
			(end -0.7874 0.4064)
			(stroke
				(width 0.1524)
				(type default)
			)
			(layer "F.SilkS")
		)
		(fp_line
			(start -0.7874 0.4064)
			(end -0.7874 -0.4064)
			(stroke
				(width 0.1524)
				(type default)
			)
			(layer "F.SilkS")
		)
		(fp_poly
			(pts
				(xy -0.5334 0.254) (xy -0.635 0.254) (xy -0.635 0.2286) (xy -0.635 -0.254) (xy -0.5334 -0.254) (xy -0.5334 -0.2794)
				(xy 0.5334 -0.2794) (xy 0.5334 -0.254) (xy 0.635 -0.254) (xy 0.635 0.254) (xy 0.5334 0.254) (xy 0.5334 0.2794)
				(xy -0.508 0.2794) (xy -0.5334 0.2794)
			)
			(stroke
				(width 0)
				(type default)
			)
			(fill no)
			(layer "F.CrtYd")
		)
		(pad "1" smd rect
			(at 0.40005 0 90)
			(size 0.4572 0.508)
			(layers "F.Cu" "F.Mask" "F.Paste")
			(net "T2_NODE2_EN_R")
		)
		(pad "2" smd rect
			(at -0.40005 0 90)
			(size 0.4572 0.508)
			(layers "F.Cu" "F.Mask" "F.Paste")
			(net "GND")
		)
	)
)
